(kicad_pcb
	(version 20241229)
	(generator "pcbnew")
	(generator_version "9.0")
	(general
		(thickness 1.62)
		(legacy_teardrops no)
	)
	(paper "A3")
	(title_block
		(title "COM Express 7 Baseboard")
		(date "2025-02-04")
		(rev "1.1.2")
		(company "Antmicro Ltd")
		(comment 1 "www.antmicro.com")
		(comment 9 "footprints 200-203 of 802")
	)
	(layers
		(0 "F.Cu" signal)
		(4 "In1.Cu" signal)
		(6 "In2.Cu" signal)
		(8 "In3.Cu" signal)
		(10 "In4.Cu" signal)
		(12 "In5.Cu" signal)
		(14 "In6.Cu" signal)
		(2 "B.Cu" signal)
		(9 "F.Adhes" user "F.Adhesive")
		(11 "B.Adhes" user "B.Adhesive")
		(13 "F.Paste" user)
		(15 "B.Paste" user)
		(5 "F.SilkS" user "F.Silkscreen")
		(7 "B.SilkS" user "B.Silkscreen")
		(1 "F.Mask" user)
		(3 "B.Mask" user)
		(17 "Dwgs.User" user "User.Drawings")
		(19 "Cmts.User" user "User.Comments")
		(21 "Eco1.User" user "User.Eco1")
		(23 "Eco2.User" user "User.Eco2")
		(25 "Edge.Cuts" user)
		(27 "Margin" user)
		(31 "F.CrtYd" user "F.Courtyard")
		(29 "B.CrtYd" user "B.Courtyard")
		(35 "F.Fab" user)
		(33 "B.Fab" user)
	)
	(footprint "antmicro-footprints:C_Pol_EIA-B"
		(layer "F.Cu")
		(at 308.825 96.74)
		(property "Reference" "C64"
			(at -4.325 1.82 0)
			(layer "F.SilkS")
			(effects
				(font
					(size 0.7 0.7)
					(thickness 0.15)
				)
				(justify left bottom)
			)
		)
		(property "Value" "C_Pol_100u_10V_KEMET-T520-B"
			(at 0 2.85 0)
			(layer "F.Fab")
			(effects
				(font
					(size 0.7 0.7)
					(thickness 0.15)
				)
				(justify left bottom)
			)
		)
		(property "Datasheet" "https://www.kemet.com/en/us/capacitors/product/T520B107M010ATE070.html"
			(at 0 0 0)
			(layer "F.Fab")
			(hide yes)
			(effects
				(font
					(size 1.27 1.27)
					(thickness 0.15)
				)
			)
		)
		(property "Author" "Antmicro"
			(at 0 0 0)
			(layer "F.Fab")
			(hide yes)
			(effects
				(font
					(size 1 1)
					(thickness 0.15)
				)
			)
		)
		(property "Dielectric" "template_dielectric"
			(at 0 0 0)
			(layer "F.Fab")
			(hide yes)
			(effects
				(font
					(size 1 1)
					(thickness 0.15)
				)
			)
		)
		(property "License" "Apache-2.0"
			(at 0 0 0)
			(layer "F.Fab")
			(hide yes)
			(effects
				(font
					(size 1 1)
					(thickness 0.15)
				)
			)
		)
		(property "MPN" "T520B107M010ATE070"
			(at 0 0 0)
			(layer "F.Fab")
			(hide yes)
			(effects
				(font
					(size 1 1)
					(thickness 0.15)
				)
			)
		)
		(property "Manufacturer" "KEMET"
			(at 0 0 0)
			(layer "F.Fab")
			(hide yes)
			(effects
				(font
					(size 1 1)
					(thickness 0.15)
				)
			)
		)
		(property "Public" "False"
			(at 0 0 0)
			(layer "F.Fab")
			(hide yes)
			(effects
				(font
					(size 1 1)
					(thickness 0.15)
				)
			)
		)
		(property "Val" "100u"
			(at 0 0 0)
			(layer "F.Fab")
			(hide yes)
			(effects
				(font
					(size 1 1)
					(thickness 0.15)
				)
			)
		)
		(property "Voltage" "10V"
			(at 0 0 0)
			(layer "F.Fab")
			(hide yes)
			(effects
				(font
					(size 1 1)
					(thickness 0.15)
				)
			)
		)
		(sheetname "Power")
		(sheetfile "power.kicad_sch")
		(attr smd)
		(fp_line
			(start -2.521 -1.676)
			(end -2.123 -1.676)
			(stroke
				(width 0.15)
				(type solid)
			)
			(layer "F.SilkS")
		)
		(fp_line
			(start -2.325 -1.475)
			(end -2.325 -1.878)
			(stroke
				(width 0.15)
				(type solid)
			)
			(layer "F.SilkS")
		)
		(fp_line
			(start -1.8 -1.6)
			(end 1.8 -1.6)
			(stroke
				(width 0.15)
				(type solid)
			)
			(layer "F.SilkS")
		)
		(fp_line
			(start -1.8 -1.3)
			(end -1.8 -1.6)
			(stroke
				(width 0.15)
				(type solid)
			)
			(layer "F.SilkS")
		)
		(fp_line
			(start -1.8 1.3)
			(end -1.8 1.6)
			(stroke
				(width 0.15)
				(type solid)
			)
			(layer "F.SilkS")
		)
		(fp_line
			(start 1.8 -1.3)
			(end 1.8 -1.6)
			(stroke
				(width 0.15)
				(type solid)
			)
			(layer "F.SilkS")
		)
		(fp_line
			(start 1.8 1.3)
			(end 1.8 1.6)
			(stroke
				(width 0.15)
				(type solid)
			)
			(layer "F.SilkS")
		)
		(fp_line
			(start 1.8 1.6)
			(end -1.8 1.6)
			(stroke
				(width 0.15)
				(type solid)
			)
			(layer "F.SilkS")
		)
		(fp_line
			(start -2.411 -1.35)
			(end -2.41 1.35)
			(stroke
				(width 0.05)
				(type solid)
			)
			(layer "F.CrtYd")
		)
		(fp_line
			(start -1.97 -1.75)
			(end -1.97 -1.35)
			(stroke
				(width 0.05)
				(type solid)
			)
			(layer "F.CrtYd")
		)
		(fp_line
			(start -1.97 -1.35)
			(end -2.41 -1.35)
			(stroke
				(width 0.05)
				(type solid)
			)
			(layer "F.CrtYd")
		)
		(fp_line
			(start -1.97 1.35)
			(end -2.41 1.35)
			(stroke
				(width 0.05)
				(type solid)
			)
			(layer "F.CrtYd")
		)
		(fp_line
			(start -1.97 1.35)
			(end -1.97 1.75)
			(stroke
				(width 0.05)
				(type solid)
			)
			(layer "F.CrtYd")
		)
		(fp_line
			(start 1.959 -1.75)
			(end -1.97 -1.75)
			(stroke
				(width 0.05)
				(type solid)
			)
			(layer "F.CrtYd")
		)
		(fp_line
			(start 1.959 -1.75)
			(end 1.959 -1.35)
			(stroke
				(width 0.05)
				(type solid)
			)
			(layer "F.CrtYd")
		)
		(fp_line
			(start 1.96 1.35)
			(end 1.96 1.75)
			(stroke
				(width 0.05)
				(type solid)
			)
			(layer "F.CrtYd")
		)
		(fp_line
			(start 1.96 1.75)
			(end -1.97 1.75)
			(stroke
				(width 0.05)
				(type solid)
			)
			(layer "F.CrtYd")
		)
		(fp_line
			(start 2.399 -1.35)
			(end 1.959 -1.35)
			(stroke
				(width 0.05)
				(type solid)
			)
			(layer "F.CrtYd")
		)
		(fp_line
			(start 2.399 -1.35)
			(end 2.4 1.35)
			(stroke
				(width 0.05)
				(type solid)
			)
			(layer "F.CrtYd")
		)
		(fp_line
			(start 2.4 1.35)
			(end 1.96 1.35)
			(stroke
				(width 0.05)
				(type solid)
			)
			(layer "F.CrtYd")
		)
		(fp_line
			(start -1.7 1.324)
			(end -1.551 1.475)
			(stroke
				(width 0.15)
				(type solid)
			)
			(layer "F.Fab")
		)
		(fp_rect
			(start -1.72 -1.5)
			(end 1.719 1.499)
			(stroke
				(width 0.15)
				(type solid)
			)
			(fill no)
			(layer "F.Fab")
		)
		(pad "1" smd roundrect
			(at -1.551 0)
			(size 1.2 2.2)
			(layers "F.Cu" "F.Mask" "F.Paste")
			(roundrect_rratio 0.1)
			(net 75 "Net-(U50-IN+)")
			(pintype "passive")
			(teardrops
				(best_length_ratio 0.2)
				(max_length 1)
				(best_width_ratio 0.9)
				(max_width 2)
				(curved_edges yes)
				(filter_ratio 0.9)
				(enabled yes)
				(allow_two_segments yes)
				(prefer_zone_connections yes)
			)
		)
		(pad "2" smd roundrect
			(at 1.55 0)
			(size 1.2 2.2)
			(layers "F.Cu" "F.Mask" "F.Paste")
			(roundrect_rratio 0.1)
			(net 1 "GND")
			(pintype "passive")
			(teardrops
				(best_length_ratio 0.2)
				(max_length 1)
				(best_width_ratio 0.9)
				(max_width 2)
				(curved_edges yes)
				(filter_ratio 0.9)
				(enabled yes)
				(allow_two_segments yes)
				(prefer_zone_connections yes)
			)
		)
	)
	(footprint "antmicro-footprints:R_0402_1005Metric"
		(layer "F.Cu")
		(at 201.70861 77.152163 90)
		(descr "Resistor SMD 0402")
		(tags "resistor SMD 0402")
		(property "Reference" "R318"
			(at -1.9 -0.5 90)
			(layer "F.SilkS")
			(effects
				(font
					(size 0.7 0.7)
					(thickness 0.15)
				)
				(justify left bottom)
			)
		)
		(property "Value" "R_2k2_0402"
			(at -1.011843 1.772047 90)
			(layer "F.Fab")
			(effects
				(font
					(size 0.7 0.7)
					(thickness 0.15)
				)
				(justify left bottom)
			)
		)
		(property "Datasheet" "https://www.bourns.com/docs/product-datasheets/cr.pdf"
			(at 0 0 90)
			(layer "F.Fab")
			(hide yes)
			(effects
				(font
					(size 1.27 1.27)
					(thickness 0.15)
				)
			)
		)
		(property "Author" "Antmicro"
			(at 278.860773 -124.556447 0)
			(layer "F.Fab")
			(hide yes)
			(effects
				(font
					(size 1 1)
					(thickness 0.15)
				)
			)
		)
		(property "License" "Apache-2.0"
			(at 278.860773 -124.556447 0)
			(layer "F.Fab")
			(hide yes)
			(effects
				(font
					(size 1 1)
					(thickness 0.15)
				)
			)
		)
		(property "MPN" "CR0402-FX-2201GLF"
			(at 278.860773 -124.556447 0)
			(layer "F.Fab")
			(hide yes)
			(effects
				(font
					(size 1 1)
					(thickness 0.15)
				)
			)
		)
		(property "Manufacturer" "Bourns"
			(at 278.860773 -124.556447 0)
			(layer "F.Fab")
			(hide yes)
			(effects
				(font
					(size 1 1)
					(thickness 0.15)
				)
			)
		)
		(property "Tolerance" "1%"
			(at 278.860773 -124.556447 0)
			(layer "F.Fab")
			(hide yes)
			(effects
				(font
					(size 1 1)
					(thickness 0.15)
				)
			)
		)
		(property "Val" "2k2"
			(at 278.860773 -124.556447 0)
			(layer "F.Fab")
			(hide yes)
			(effects
				(font
					(size 1 1)
					(thickness 0.15)
				)
			)
		)
		(sheetname "Power")
		(sheetfile "power.kicad_sch")
		(attr smd)
		(fp_rect
			(start -0.925 -0.47)
			(end 0.925 0.47)
			(stroke
				(width 0.05)
				(type default)
			)
			(fill no)
			(layer "F.CrtYd")
		)
		(fp_rect
			(start -0.5 -0.25)
			(end 0.5 0.25)
			(stroke
				(width 0.15)
				(type solid)
			)
			(fill no)
			(layer "F.Fab")
		)
		(pad "1" smd roundrect
			(at -0.48 0 90)
			(size 0.59 0.64)
			(layers "F.Cu" "F.Mask" "F.Paste")
			(roundrect_rratio 0.25)
			(net 988 "Net-(Q13-C)")
			(pintype "passive")
			(teardrops
				(best_length_ratio 0.2)
				(max_length 1)
				(best_width_ratio 0.9)
				(max_width 2)
				(curved_edges yes)
				(filter_ratio 0.9)
				(enabled yes)
				(allow_two_segments yes)
				(prefer_zone_connections yes)
			)
		)
		(pad "2" smd roundrect
			(at 0.48 0 90)
			(size 0.59 0.64)
			(layers "F.Cu" "F.Mask" "F.Paste")
			(roundrect_rratio 0.25)
			(net 979 "Net-(D26-C)")
			(pintype "passive")
			(teardrops
				(best_length_ratio 0.2)
				(max_length 1)
				(best_width_ratio 0.9)
				(max_width 2)
				(curved_edges yes)
				(filter_ratio 0.9)
				(enabled yes)
				(allow_two_segments yes)
				(prefer_zone_connections yes)
			)
		)
	)
	(footprint "antmicro-footprints:R_0402_1005Metric"
		(layer "F.Cu")
		(at 199.70861 77.152163 90)
		(descr "Resistor SMD 0402")
		(tags "resistor SMD 0402")
		(property "Reference" "R319"
			(at -1.9 -0.5 90)
			(layer "F.SilkS")
			(effects
				(font
					(size 0.7 0.7)
					(thickness 0.15)
				)
				(justify left bottom)
			)
		)
		(property "Value" "R_2k2_0402"
			(at -1.011843 1.772047 90)
			(layer "F.Fab")
			(effects
				(font
					(size 0.7 0.7)
					(thickness 0.15)
				)
				(justify left bottom)
			)
		)
		(property "Datasheet" "https://www.bourns.com/docs/product-datasheets/cr.pdf"
			(at 0 0 90)
			(layer "F.Fab")
			(hide yes)
			(effects
				(font
					(size 1.27 1.27)
					(thickness 0.15)
				)
			)
		)
		(property "Author" "Antmicro"
			(at 276.860773 -122.556447 0)
			(layer "F.Fab")
			(hide yes)
			(effects
				(font
					(size 1 1)
					(thickness 0.15)
				)
			)
		)
		(property "License" "Apache-2.0"
			(at 276.860773 -122.556447 0)
			(layer "F.Fab")
			(hide yes)
			(effects
				(font
					(size 1 1)
					(thickness 0.15)
				)
			)
		)
		(property "MPN" "CR0402-FX-2201GLF"
			(at 276.860773 -122.556447 0)
			(layer "F.Fab")
			(hide yes)
			(effects
				(font
					(size 1 1)
					(thickness 0.15)
				)
			)
		)
		(property "Manufacturer" "Bourns"
			(at 276.860773 -122.556447 0)
			(layer "F.Fab")
			(hide yes)
			(effects
				(font
					(size 1 1)
					(thickness 0.15)
				)
			)
		)
		(property "Tolerance" "1%"
			(at 276.860773 -122.556447 0)
			(layer "F.Fab")
			(hide yes)
			(effects
				(font
					(size 1 1)
					(thickness 0.15)
				)
			)
		)
		(property "Val" "2k2"
			(at 276.860773 -122.556447 0)
			(layer "F.Fab")
			(hide yes)
			(effects
				(font
					(size 1 1)
					(thickness 0.15)
				)
			)
		)
		(sheetname "Power")
		(sheetfile "power.kicad_sch")
		(attr smd)
		(fp_rect
			(start -0.925 -0.47)
			(end 0.925 0.47)
			(stroke
				(width 0.05)
				(type default)
			)
			(fill no)
			(layer "F.CrtYd")
		)
		(fp_rect
			(start -0.5 -0.25)
			(end 0.5 0.25)
			(stroke
				(width 0.15)
				(type solid)
			)
			(fill no)
			(layer "F.Fab")
		)
		(pad "1" smd roundrect
			(at -0.48 0 90)
			(size 0.59 0.64)
			(layers "F.Cu" "F.Mask" "F.Paste")
			(roundrect_rratio 0.25)
			(net 990 "Net-(Q14-C)")
			(pintype "passive")
			(teardrops
				(best_length_ratio 0.2)
				(max_length 1)
				(best_width_ratio 0.9)
				(max_width 2)
				(curved_edges yes)
				(filter_ratio 0.9)
				(enabled yes)
				(allow_two_segments yes)
				(prefer_zone_connections yes)
			)
		)
		(pad "2" smd roundrect
			(at 0.48 0 90)
			(size 0.59 0.64)
			(layers "F.Cu" "F.Mask" "F.Paste")
			(roundrect_rratio 0.25)
			(net 980 "Net-(D27-C)")
			(pintype "passive")
			(teardrops
				(best_length_ratio 0.2)
				(max_length 1)
				(best_width_ratio 0.9)
				(max_width 2)
				(curved_edges yes)
				(filter_ratio 0.9)
				(enabled yes)
				(allow_two_segments yes)
				(prefer_zone_connections yes)
			)
		)
	)
	(footprint "antmicro-footprints:SOT-23-3"
		(layer "F.Cu")
		(at 199 80.75 90)
		(property "Reference" "Q14"
			(at -1.45 -1.75 90)
			(layer "F.SilkS")
			(effects
				(font
					(size 0.7 0.7)
					(thickness 0.15)
				)
				(justify left bottom)
			)
		)
		(property "Value" "MMBT3904LT1G"
			(at -1.9 2.7 90)
			(layer "F.Fab")
			(effects
				(font
					(size 0.7 0.7)
					(thickness 0.15)
				)
				(justify left bottom)
			)
		)
		(property "Datasheet" "https://eu.mouser.com/datasheet/2/308/1/MMBT3904LT1_D-2316262.pdf"
			(at 0 0 90)
			(layer "F.Fab")
			(hide yes)
			(effects
				(font
					(size 1.27 1.27)
					(thickness 0.15)
				)
			)
		)
		(property "Author" "Antmicro"
			(at 282.725773 -121.441447 0)
			(layer "F.Fab")
			(hide yes)
			(effects
				(font
					(size 1 1)
					(thickness 0.15)
				)
			)
		)
		(property "License" "Apache-2.0"
			(at 282.725773 -121.441447 0)
			(layer "F.Fab")
			(hide yes)
			(effects
				(font
					(size 1 1)
					(thickness 0.15)
				)
			)
		)
		(property "MPN" "MMBT3904LT1G"
			(at 282.725773 -121.441447 0)
			(layer "F.Fab")
			(hide yes)
			(effects
				(font
					(size 1 1)
					(thickness 0.15)
				)
			)
		)
		(property "Manufacturer" "Onsemi"
			(at 282.725773 -121.441447 0)
			(layer "F.Fab")
			(hide yes)
			(effects
				(font
					(size 1 1)
					(thickness 0.15)
				)
			)
		)
		(property "Public" "False"
			(at 282.725773 -121.441447 0)
			(layer "F.Fab")
			(hide yes)
			(effects
				(font
					(size 1 1)
					(thickness 0.15)
				)
			)
		)
		(property ki_fp_filters "SOT?323*")
		(sheetname "Power")
		(sheetfile "power.kicad_sch")
		(attr smd)
		(fp_line
			(start 0.7 -1.5)
			(end -0.7 -1.5)
			(stroke
				(width 0.15)
				(type solid)
			)
			(layer "F.SilkS")
		)
		(fp_line
			(start -0.85 -1.35)
			(end -0.7 -1.5)
			(stroke
				(width 0.15)
				(type solid)
			)
			(layer "F.SilkS")
		)
		(fp_line
			(start -1.45 -1.35)
			(end -0.85 -1.35)
			(stroke
				(width 0.15)
				(type solid)
			)
			(layer "F.SilkS")
		)
		(fp_line
			(start 0.7 -0.4)
			(end 0.7 -1.5)
			(stroke
				(width 0.15)
				(type solid)
			)
			(layer "F.SilkS")
		)
		(fp_line
			(start 0.7 0.4)
			(end 0.7 1.5)
			(stroke
				(width 0.15)
				(type solid)
			)
			(layer "F.SilkS")
		)
		(fp_line
			(start 0.7 1.5)
			(end -0.7 1.5)
			(stroke
				(width 0.15)
				(type solid)
			)
			(layer "F.SilkS")
		)
		(fp_line
			(start -0.7 1.5)
			(end -0.7 1.35)
			(stroke
				(width 0.15)
				(type solid)
			)
			(layer "F.SilkS")
		)
		(fp_line
			(start 0.825 -1.6)
			(end 0.825 -0.45)
			(stroke
				(width 0.05)
				(type solid)
			)
			(layer "F.CrtYd")
		)
		(fp_line
			(start -0.9 -1.6)
			(end 0.825 -1.6)
			(stroke
				(width 0.05)
				(type solid)
			)
			(layer "F.CrtYd")
		)
		(fp_line
			(start -0.9 -1.6)
			(end -0.9 -1.4)
			(stroke
				(width 0.05)
				(type solid)
			)
			(layer "F.CrtYd")
		)
		(fp_line
			(start -0.9 -1.4)
			(end -1.75 -1.4)
			(stroke
				(width 0.05)
				(type solid)
			)
			(layer "F.CrtYd")
		)
		(fp_line
			(start -0.85 -0.5)
			(end -1.75 -0.5)
			(stroke
				(width 0.05)
				(type solid)
			)
			(layer "F.CrtYd")
		)
		(fp_line
			(start -1.75 -0.5)
			(end -1.75 -1.4)
			(stroke
				(width 0.05)
				(type solid)
			)
			(layer "F.CrtYd")
		)
		(fp_line
			(start 1.75 -0.45)
			(end 1.75 0.45)
			(stroke
				(width 0.05)
				(type solid)
			)
			(layer "F.CrtYd")
		)
		(fp_line
			(start 0.825 -0.45)
			(end 1.75 -0.45)
			(stroke
				(width 0.05)
				(type solid)
			)
			(layer "F.CrtYd")
		)
		(fp_line
			(start 1.75 0.45)
			(end 0.85 0.45)
			(stroke
				(width 0.05)
				(type solid)
			)
			(layer "F.CrtYd")
		)
		(fp_line
			(start 0.85 0.45)
			(end 0.85 1.65)
			(stroke
				(width 0.05)
				(type solid)
			)
			(layer "F.CrtYd")
		)
		(fp_line
			(start -0.85 0.5)
			(end -0.85 -0.5)
			(stroke
				(width 0.05)
				(type solid)
			)
			(layer "F.CrtYd")
		)
		(fp_line
			(start -1.75 0.5)
			(end -0.85 0.5)
			(stroke
				(width 0.05)
				(type solid)
			)
			(layer "F.CrtYd")
		)
		(fp_line
			(start -0.85 1.4)
			(end -1.75 1.4)
			(stroke
				(width 0.05)
				(type solid)
			)
			(layer "F.CrtYd")
		)
		(fp_line
			(start -1.75 1.4)
			(end -1.75 0.5)
			(stroke
				(width 0.05)
				(type solid)
			)
			(layer "F.CrtYd")
		)
		(fp_line
			(start 0.85 1.65)
			(end -0.85 1.65)
			(stroke
				(width 0.05)
				(type solid)
			)
			(layer "F.CrtYd")
		)
		(fp_line
			(start -0.85 1.65)
			(end -0.85 1.4)
			(stroke
				(width 0.05)
				(type solid)
			)
			(layer "F.CrtYd")
		)
		(fp_line
			(start -0.437 -1.526)
			(end 0.688 -1.526)
			(stroke
				(width 0.15)
				(type solid)
			)
			(layer "F.Fab")
		)
		(fp_line
			(start -0.437 -1.526)
			(end -0.712 -1.325)
			(stroke
				(width 0.15)
				(type solid)
			)
			(layer "F.Fab")
		)
		(fp_line
			(start -0.712 -1.325)
			(end -0.712 1.523)
			(stroke
				(width 0.15)
				(type solid)
			)
			(layer "F.Fab")
		)
		(fp_line
			(start 0.688 1.519)
			(end 0.688 -1.52)
			(stroke
				(width 0.15)
				(type solid)
			)
			(layer "F.Fab")
		)
		(fp_line
			(start -0.712 1.519)
			(end 0.688 1.519)
			(stroke
				(width 0.15)
				(type solid)
			)
			(layer "F.Fab")
		)
		(pad "1" smd roundrect
			(at -1.1 -0.951 90)
			(size 1 0.6)
			(layers "F.Cu" "F.Mask" "F.Paste")
			(roundrect_rratio 0.15)
			(net 989 "Net-(Q14-B)")
			(pinfunction "B")
			(pintype "input")
			(teardrops
				(best_length_ratio 0.2)
				(max_length 1)
				(best_width_ratio 0.9)
				(max_width 2)
				(curved_edges yes)
				(filter_ratio 0.9)
				(enabled yes)
				(allow_two_segments yes)
				(prefer_zone_connections yes)
			)
		)
		(pad "2" smd roundrect
			(at -1.1 0.949 90)
			(size 1 0.6)
			(layers "F.Cu" "F.Mask" "F.Paste")
			(roundrect_rratio 0.15)
			(net 1 "GND")
			(pinfunction "E")
			(pintype "passive")
			(teardrops
				(best_length_ratio 0.2)
				(max_length 1)
				(best_width_ratio 0.9)
				(max_width 2)
				(curved_edges yes)
				(filter_ratio 0.9)
				(enabled yes)
				(allow_two_segments yes)
				(prefer_zone_connections yes)
			)
		)
		(pad "3" smd roundrect
			(at 1.1 -0.0005 90)
			(size 1 0.6)
			(layers "F.Cu" "F.Mask" "F.Paste")
			(roundrect_rratio 0.15)
			(net 990 "Net-(Q14-C)")
			(pinfunction "C")
			(pintype "passive")
			(teardrops
				(best_length_ratio 0.2)
				(max_length 1)
				(best_width_ratio 0.9)
				(max_width 2)
				(curved_edges yes)
				(filter_ratio 0.9)
				(enabled yes)
				(allow_two_segments yes)
				(prefer_zone_connections yes)
			)
		)
	)
)
